# SCM (Grand Teton) — schematic netlist excerpt (pin names and nets, part order shuffled) for the footprints in the layout excerpt that follows; sources: Cadence DE-HDL packaged netlist, KiCad conversion of 12092022_DA0F0TMDCD0_F0T_Management_Board_D_brd_V3_OCP.brd

R516  Q_RES  33.2 1% CHIP  pkg 0402LF  page 32 : A = JTAG_SCM_PLD_TDI ; B = JTAG_SCM_CONN_TDI
R390  Q_RES  33.2 1% CHIP  pkg 0402LF  page 49 : A = FM_ID_LED ; B = FM_ID_R_LED

(kicad_pcb
	(version 20260206)
	(generator "pcbnew")
	(generator_version "10.0")
	(general
		(thickness 1.6)
		(legacy_teardrops no)
	)
	(paper "A4")
	(title_block
		(title "12092022_DA0F0TMDCD0_F0T_Management_Board_D_brd_V3_OCP.brd")
		(comment 1 "Grand Teton / footprints 291-292 of 1440")
	)
	(layers
		(0 "F.Cu" signal "TOP")
		(4 "In1.Cu" signal "GND")
		(6 "In2.Cu" signal "IN1")
		(8 "In3.Cu" signal "GND1")
		(10 "In4.Cu" signal "IN2")
		(12 "In5.Cu" signal "VCC")
		(14 "In6.Cu" signal "VCC1")
		(16 "In7.Cu" signal "IN3")
		(18 "In8.Cu" signal "GND2")
		(20 "In9.Cu" signal "IN4")
		(22 "In10.Cu" signal "GND3")
		(2 "B.Cu" signal "BOTTOM")
		(9 "F.Adhes" user "F.Adhesive")
		(11 "B.Adhes" user "B.Adhesive")
		(13 "F.Paste" user "Package Geometry/Pastemask Top")
		(15 "B.Paste" user "Package Geometry/Pastemask Bottom")
		(5 "F.SilkS" user "Ref Des/Silkscreen Top")
		(7 "B.SilkS" user "Ref Des/Silkscreen Bottom")
		(1 "F.Mask" user "Board Geometry/Soldermask Top")
		(3 "B.Mask" user "Board Geometry/Soldermask Bottom")
		(17 "Dwgs.User" user "User.Drawings")
		(19 "Cmts.User" user "User.Comments")
		(21 "Eco1.User" user "User.Eco1")
		(23 "Eco2.User" user "User.Eco2")
		(25 "Edge.Cuts" user "Board Geometry/Outline")
		(27 "Margin" user)
		(31 "F.CrtYd" user "Package Geometry/Place Bound Top")
		(29 "B.CrtYd" user "Package Geometry/Place Bound Bottom")
		(35 "F.Fab" user "Ref Des/Assembly Top")
		(33 "B.Fab" user "Ref Des/Assembly Bottom")
	)
	(footprint ""
		(layer "F.Cu")
		(at 32.766 -12.7 180)
		(property "Reference" "R390"
			(at 0 0 180)
			(layer "F.SilkS")
			(hide yes)
			(effects
				(font
					(size 1.27 1.27)
				)
			)
		)
		(property "Value" ""
			(at 0 0 180)
			(layer "F.Fab")
			(effects
				(font
					(size 1.27 1.27)
				)
			)
		)
		(duplicate_pad_numbers_are_jumpers no)
		(fp_line
			(start 0.7874 0.4064)
			(end -0.7874 0.4064)
			(stroke
				(width 0.1524)
				(type default)
			)
			(layer "F.SilkS")
		)
		(fp_line
			(start 0.7874 -0.4064)
			(end 0.7874 0.4064)
			(stroke
				(width 0.1524)
				(type default)
			)
			(layer "F.SilkS")
		)
		(fp_line
			(start -0.7874 0.4064)
			(end -0.7874 -0.4064)
			(stroke
				(width 0.1524)
				(type default)
			)
			(layer "F.SilkS")
		)
		(fp_line
			(start -0.7874 -0.4064)
			(end 0.7874 -0.4064)
			(stroke
				(width 0.1524)
				(type default)
			)
			(layer "F.SilkS")
		)
		(fp_line
			(start 0.67945 0.3048)
			(end 0.120396 0.3048)
			(stroke
				(width 0.1)
				(type default)
			)
			(layer "F.Fab")
		)
		(fp_line
			(start 0.67945 -0.3048)
			(end 0.67945 0.3048)
			(stroke
				(width 0.1)
				(type default)
			)
			(layer "F.Fab")
		)
		(fp_line
			(start 0.12065 -0.2794)
			(end 0.12065 -0.3048)
			(stroke
				(width 0.1)
				(type default)
			)
			(layer "F.Fab")
		)
		(fp_line
			(start 0.12065 -0.3048)
			(end 0.67945 -0.3048)
			(stroke
				(width 0.1)
				(type default)
			)
			(layer "F.Fab")
		)
		(fp_line
			(start 0.120396 0.3048)
			(end 0.120396 0.2794)
			(stroke
				(width 0.1)
				(type default)
			)
			(layer "F.Fab")
		)
		(fp_line
			(start 0.120396 0.2794)
			(end -0.12065 0.2794)
			(stroke
				(width 0.1)
				(type default)
			)
			(layer "F.Fab")
		)
		(fp_line
			(start -0.12065 0.3048)
			(end -0.67945 0.3048)
			(stroke
				(width 0.1)
				(type default)
			)
			(layer "F.Fab")
		)
		(fp_line
			(start -0.12065 0.2794)
			(end -0.12065 0.3048)
			(stroke
				(width 0.1)
				(type default)
			)
			(layer "F.Fab")
		)
		(fp_line
			(start -0.12065 -0.2794)
			(end 0.12065 -0.2794)
			(stroke
				(width 0.1)
				(type default)
			)
			(layer "F.Fab")
		)
		(fp_line
			(start -0.12065 -0.305054)
			(end -0.12065 -0.2794)
			(stroke
				(width 0.1)
				(type default)
			)
			(layer "F.Fab")
		)
		(fp_line
			(start -0.67945 0.3048)
			(end -0.67945 -0.305054)
			(stroke
				(width 0.1)
				(type default)
			)
			(layer "F.Fab")
		)
		(fp_line
			(start -0.67945 -0.305054)
			(end -0.12065 -0.305054)
			(stroke
				(width 0.1)
				(type default)
			)
			(layer "F.Fab")
		)
		(pad "1" smd circle
			(at -0.40005 0 180)
			(size 0 0)
			(layers "F.Cu" "F.Mask" "F.Paste")
			(net "FM_ID_LED")
		)
		(pad "2" smd circle
			(at 0.40005 0 180)
			(size 0 0)
			(layers "F.Cu" "F.Mask" "F.Paste")
			(net "FM_ID_R_LED")
		)
	)
	(footprint ""
		(layer "F.Cu")
		(at 10.287 -100.076 -90)
		(property "Reference" "R516"
			(at 0 0 270)
			(layer "F.SilkS")
			(hide yes)
			(effects
				(font
					(size 1.27 1.27)
				)
			)
		)
		(property "Value" ""
			(at 0 0 270)
			(layer "F.Fab")
			(effects
				(font
					(size 1.27 1.27)
				)
			)
		)
		(duplicate_pad_numbers_are_jumpers no)
		(fp_line
			(start -0.7874 0.4064)
			(end -0.7874 -0.4064)
			(stroke
				(width 0.1524)
				(type default)
			)
			(layer "F.SilkS")
		)
		(fp_line
			(start 0.7874 0.4064)
			(end -0.7874 0.4064)
			(stroke
				(width 0.1524)
				(type default)
			)
			(layer "F.SilkS")
		)
		(fp_line
			(start -0.7874 -0.4064)
			(end 0.7874 -0.4064)
			(stroke
				(width 0.1524)
				(type default)
			)
			(layer "F.SilkS")
		)
		(fp_line
			(start 0.7874 -0.4064)
			(end 0.7874 0.4064)
			(stroke
				(width 0.1524)
				(type default)
			)
			(layer "F.SilkS")
		)
		(fp_line
			(start -0.67945 0.3048)
			(end -0.67945 -0.305054)
			(stroke
				(width 0.1)
				(type default)
			)
			(layer "F.Fab")
		)
		(fp_line
			(start -0.12065 0.3048)
			(end -0.67945 0.3048)
			(stroke
				(width 0.1)
				(type default)
			)
			(layer "F.Fab")
		)
		(fp_line
			(start 0.120396 0.3048)
			(end 0.120396 0.2794)
			(stroke
				(width 0.1)
				(type default)
			)
			(layer "F.Fab")
		)
		(fp_line
			(start 0.67945 0.3048)
			(end 0.120396 0.3048)
			(stroke
				(width 0.1)
				(type default)
			)
			(layer "F.Fab")
		)
		(fp_line
			(start -0.12065 0.2794)
			(end -0.12065 0.3048)
			(stroke
				(width 0.1)
				(type default)
			)
			(layer "F.Fab")
		)
		(fp_line
			(start 0.120396 0.2794)
			(end -0.12065 0.2794)
			(stroke
				(width 0.1)
				(type default)
			)
			(layer "F.Fab")
		)
		(fp_line
			(start -0.12065 -0.2794)
			(end 0.12065 -0.2794)
			(stroke
				(width 0.1)
				(type default)
			)
			(layer "F.Fab")
		)
		(fp_line
			(start 0.12065 -0.2794)
			(end 0.12065 -0.3048)
			(stroke
				(width 0.1)
				(type default)
			)
			(layer "F.Fab")
		)
		(fp_line
			(start 0.12065 -0.3048)
			(end 0.67945 -0.3048)
			(stroke
				(width 0.1)
				(type default)
			)
			(layer "F.Fab")
		)
		(fp_line
			(start 0.67945 -0.3048)
			(end 0.67945 0.3048)
			(stroke
				(width 0.1)
				(type default)
			)
			(layer "F.Fab")
		)
		(fp_line
			(start -0.67945 -0.305054)
			(end -0.12065 -0.305054)
			(stroke
				(width 0.1)
				(type default)
			)
			(layer "F.Fab")
		)
		(fp_line
			(start -0.12065 -0.305054)
			(end -0.12065 -0.2794)
			(stroke
				(width 0.1)
				(type default)
			)
			(layer "F.Fab")
		)
		(pad "1" smd circle
			(at -0.40005 0 270)
			(size 0 0)
			(layers "F.Cu" "F.Mask" "F.Paste")
			(net "JTAG_SCM_PLD_TDI")
		)
		(pad "2" smd circle
			(at 0.40005 0 270)
			(size 0 0)
			(layers "F.Cu" "F.Mask" "F.Paste")
			(net "JTAG_SCM_CONN_TDI")
		)
	)
)
